# S9S_MB_2U (Grand Teton) — schematic netlist excerpt (pin names and nets, part order shuffled) for the footprints in the layout excerpt that follows; sources: Cadence DE-HDL packaged netlist, KiCad conversion of 03242023_DA0F0TMBIJ0_F0T_Motherboard_J_brd_V01_OCP.brd

R4659  Q_RES  0 5% CHIP  pkg 0402LF  page 167 : A = P2E_MB_BMC_TX_C_DP<0> ; B = P2E_MB_BMC_TX_C_R1_DP<0>
PD114  DIODE_TVS  SMF14A IC  pkg SOD123F  page 192 : A = GND ; C = P12V_AUX

(kicad_pcb
	(version 20260206)
	(generator "pcbnew")
	(generator_version "10.0")
	(general
		(thickness 1.6)
		(legacy_teardrops no)
	)
	(paper "A4")
	(title_block
		(title "03242023_DA0F0TMBIJ0_F0T_Motherboard_J_brd_V01_OCP.brd")
		(comment 1 "Grand Teton / footprints 275-276 of 6105")
	)
	(layers
		(0 "F.Cu" signal "TOP")
		(4 "In1.Cu" signal "GND")
		(6 "In2.Cu" signal "IN1")
		(8 "In3.Cu" signal "GND1")
		(10 "In4.Cu" signal "IN2")
		(12 "In5.Cu" signal "GND2")
		(14 "In6.Cu" signal "IN3")
		(16 "In7.Cu" signal "GND3")
		(18 "In8.Cu" signal "VCC")
		(20 "In9.Cu" signal "VCC1")
		(22 "In10.Cu" signal "GND4")
		(24 "In11.Cu" signal "IN4")
		(26 "In12.Cu" signal "GND5")
		(28 "In13.Cu" signal "IN5")
		(30 "In14.Cu" signal "GND6")
		(32 "In15.Cu" signal "IN6")
		(34 "In16.Cu" signal "GND7")
		(2 "B.Cu" signal "BOTTOM")
		(9 "F.Adhes" user "F.Adhesive")
		(11 "B.Adhes" user "B.Adhesive")
		(13 "F.Paste" user "Package Geometry/Pastemask Top")
		(15 "B.Paste" user "Package Geometry/Pastemask Bottom")
		(5 "F.SilkS" user "Ref Des/Silkscreen Top")
		(7 "B.SilkS" user "Ref Des/Silkscreen Bottom")
		(1 "F.Mask" user "Board Geometry/Soldermask Top")
		(3 "B.Mask" user "Board Geometry/Soldermask Bottom")
		(17 "Dwgs.User" user "User.Drawings")
		(19 "Cmts.User" user "User.Comments")
		(21 "Eco1.User" user "User.Eco1")
		(23 "Eco2.User" user "User.Eco2")
		(25 "Edge.Cuts" user "Board Geometry/Outline")
		(27 "Margin" user)
		(31 "F.CrtYd" user "Package Geometry/Place Bound Top")
		(29 "B.CrtYd" user "Package Geometry/Place Bound Bottom")
		(35 "F.Fab" user "Ref Des/Assembly Top")
		(33 "B.Fab" user "Ref Des/Assembly Bottom")
	)
	(footprint ""
		(layer "F.Cu")
		(at 259.710936 -38.738556 90)
		(property "Reference" "PD114"
			(at 4.87172 -1.177036 0)
			(unlocked yes)
			(layer "F.SilkS")
			(effects
				(font
					(size 0.7874 0.5842)
					(thickness 0.1524)
				)
				(justify left)
			)
		)
		(property "Value" ""
			(at 0 0 90)
			(layer "F.Fab")
			(effects
				(font
					(size 1.27 1.27)
				)
			)
		)
		(duplicate_pad_numbers_are_jumpers no)
		(fp_line
			(start 2.631186 -0.999998)
			(end -2.250186 -0.999998)
			(stroke
				(width 0.1524)
				(type default)
			)
			(layer "F.SilkS")
		)
		(fp_line
			(start -2.250186 -0.999998)
			(end -2.250186 0.999998)
			(stroke
				(width 0.1524)
				(type default)
			)
			(layer "F.SilkS")
		)
		(fp_line
			(start 0.381 -0.4318)
			(end 0.381 0.3302)
			(stroke
				(width 0.1524)
				(type default)
			)
			(layer "F.SilkS")
		)
		(fp_line
			(start -0.381 -0.4318)
			(end 0.381 -0.0508)
			(stroke
				(width 0.1524)
				(type default)
			)
			(layer "F.SilkS")
		)
		(fp_line
			(start 0.381 -0.0508)
			(end 0.635 -0.0508)
			(stroke
				(width 0.1524)
				(type default)
			)
			(layer "F.SilkS")
		)
		(fp_line
			(start 0.381 -0.0508)
			(end -0.381 0.3302)
			(stroke
				(width 0.1524)
				(type default)
			)
			(layer "F.SilkS")
		)
		(fp_line
			(start -0.381 -0.0508)
			(end -0.6604 -0.0508)
			(stroke
				(width 0.1524)
				(type default)
			)
			(layer "F.SilkS")
		)
		(fp_line
			(start -0.381 0.3302)
			(end -0.381 -0.4318)
			(stroke
				(width 0.1524)
				(type default)
			)
			(layer "F.SilkS")
		)
		(fp_line
			(start 2.631186 0.999998)
			(end 2.631186 -0.999998)
			(stroke
				(width 0.1524)
				(type default)
			)
			(layer "F.SilkS")
		)
		(fp_line
			(start -2.250186 0.999998)
			(end 2.631186 0.999998)
			(stroke
				(width 0.1524)
				(type default)
			)
			(layer "F.SilkS")
		)
		(fp_rect
			(start 2.1844 -0.9652)
			(end 2.6162 1.016)
			(stroke
				(width 0)
				(type default)
			)
			(fill yes)
			(layer "F.SilkS")
		)
		(fp_line
			(start 1.450086 -0.999998)
			(end -1.450086 -0.999998)
			(stroke
				(width 0.1)
				(type default)
			)
			(layer "F.Fab")
		)
		(fp_line
			(start -1.450086 -0.999998)
			(end -1.450086 0.999998)
			(stroke
				(width 0.1)
				(type default)
			)
			(layer "F.Fab")
		)
		(fp_line
			(start 1.450086 0.999998)
			(end 1.450086 -0.999998)
			(stroke
				(width 0.1)
				(type default)
			)
			(layer "F.Fab")
		)
		(fp_line
			(start -1.450086 0.999998)
			(end 1.450086 0.999998)
			(stroke
				(width 0.1)
				(type default)
			)
			(layer "F.Fab")
		)
		(fp_text user "-"
			(at 2.4384 -0.22225 90)
			(unlocked yes)
			(layer "F.SilkS")
			(effects
				(font
					(size 1.905 1.4224)
					(thickness 0.1524)
				)
				(justify left)
			)
		)
		(fp_text user "+"
			(at -3.83921 1.491234 90)
			(unlocked yes)
			(layer "F.SilkS")
			(effects
				(font
					(size 1.905 1.4224)
					(thickness 0.1524)
				)
				(justify left)
			)
		)
		(fp_text user "-"
			(at 2.4384 -0.22225 90)
			(unlocked yes)
			(layer "F.Fab")
			(effects
				(font
					(size 1.905 1.4224)
					(thickness 0.1524)
				)
				(justify left)
			)
		)
		(fp_text user "+"
			(at -3.4798 -0.22225 90)
			(unlocked yes)
			(layer "F.Fab")
			(effects
				(font
					(size 1.905 1.4224)
					(thickness 0.1524)
				)
				(justify left)
			)
		)
		(pad "A" smd rect
			(at -1.450086 0 90)
			(size 1.3208 1.4224)
			(layers "F.Cu" "F.Mask" "F.Paste")
			(net "GND")
		)
		(pad "C" smd rect
			(at 1.450086 0 90)
			(size 1.3208 1.4224)
			(layers "F.Cu" "F.Mask" "F.Paste")
			(net "P12V_AUX")
		)
	)
	(footprint ""
		(layer "F.Cu")
		(at 19.19859 -385.865624 90)
		(property "Reference" "R4659"
			(at 0 0 90)
			(layer "F.SilkS")
			(hide yes)
			(effects
				(font
					(size 1.27 1.27)
				)
			)
		)
		(property "Value" ""
			(at 0 0 90)
			(layer "F.Fab")
			(effects
				(font
					(size 1.27 1.27)
				)
			)
		)
		(duplicate_pad_numbers_are_jumpers no)
		(fp_line
			(start -0.7874 -0.4064)
			(end 0.7874 -0.4064)
			(stroke
				(width 0.1524)
				(type default)
			)
			(layer "F.SilkS")
		)
		(fp_line
			(start 0.7874 0.4064)
			(end -0.001524 0.4064)
			(stroke
				(width 0.1524)
				(type default)
			)
			(layer "F.SilkS")
		)
		(fp_line
			(start -0.7874 0.4064)
			(end -0.7874 -0.4064)
			(stroke
				(width 0.1524)
				(type default)
			)
			(layer "F.SilkS")
		)
		(fp_line
			(start -0.12065 -0.305054)
			(end -0.12065 -0.2794)
			(stroke
				(width 0.1)
				(type default)
			)
			(layer "F.Fab")
		)
		(fp_line
			(start -0.67945 -0.305054)
			(end -0.12065 -0.305054)
			(stroke
				(width 0.1)
				(type default)
			)
			(layer "F.Fab")
		)
		(fp_line
			(start 0.67945 -0.3048)
			(end 0.67945 0.3048)
			(stroke
				(width 0.1)
				(type default)
			)
			(layer "F.Fab")
		)
		(fp_line
			(start 0.12065 -0.3048)
			(end 0.67945 -0.3048)
			(stroke
				(width 0.1)
				(type default)
			)
			(layer "F.Fab")
		)
		(fp_line
			(start 0.12065 -0.2794)
			(end 0.12065 -0.3048)
			(stroke
				(width 0.1)
				(type default)
			)
			(layer "F.Fab")
		)
		(fp_line
			(start -0.12065 -0.2794)
			(end 0.12065 -0.2794)
			(stroke
				(width 0.1)
				(type default)
			)
			(layer "F.Fab")
		)
		(fp_line
			(start 0.120396 0.2794)
			(end -0.12065 0.2794)
			(stroke
				(width 0.1)
				(type default)
			)
			(layer "F.Fab")
		)
		(fp_line
			(start -0.12065 0.2794)
			(end -0.12065 0.3048)
			(stroke
				(width 0.1)
				(type default)
			)
			(layer "F.Fab")
		)
		(fp_line
			(start 0.67945 0.3048)
			(end 0.120396 0.3048)
			(stroke
				(width 0.1)
				(type default)
			)
			(layer "F.Fab")
		)
		(fp_line
			(start 0.120396 0.3048)
			(end 0.120396 0.2794)
			(stroke
				(width 0.1)
				(type default)
			)
			(layer "F.Fab")
		)
		(fp_line
			(start -0.12065 0.3048)
			(end -0.67945 0.3048)
			(stroke
				(width 0.1)
				(type default)
			)
			(layer "F.Fab")
		)
		(fp_line
			(start -0.67945 0.3048)
			(end -0.67945 -0.305054)
			(stroke
				(width 0.1)
				(type default)
			)
			(layer "F.Fab")
		)
		(pad "1" smd rect
			(at -0.40005 0 270)
			(size 0.4572 0.508)
			(layers "F.Cu" "F.Mask" "F.Paste")
			(net "P2E_MB_BMC_TX_C_DP<0>")
		)
		(pad "2" smd rect
			(at 0.40005 0 270)
			(size 0.4572 0.508)
			(layers "F.Cu" "F.Mask" "F.Paste")
			(net "P2E_MB_BMC_TX_C_R1_DP<0>")
		)
	)
)
